# SCM (Grand Teton) — schematic netlist excerpt (pin names and nets, part order shuffled) for the footprints in the layout excerpt that follows; sources: Cadence DE-HDL packaged netlist, KiCad conversion of 12092022_DA0F0TMDCD0_F0T_Management_Board_D_brd_V3_OCP.brd

C25  Q_CAP  0.1UF 25V 10% X7R  pkg 0402  page 12 : A = P2E_PCH_TX_DN ; B = P2E_PCH_TX_C_DN

U7  NC7SB3157  NC7SB3157P6X IC  pkg SMLF  page 31
  B1  = SPA_SOUT_SW_DBG_R
  GND  = GND
  B0  = UART_SYS_DBG_TX_R
  A  = SPA_SOUT_SW_BUF_R
  VCC  = P3V3_AUX
  S  = FM_DBG_SW_N

(kicad_pcb
	(version 20260206)
	(generator "pcbnew")
	(generator_version "10.0")
	(general
		(thickness 1.6)
		(legacy_teardrops no)
	)
	(paper "A4")
	(title_block
		(title "12092022_DA0F0TMDCD0_F0T_Management_Board_D_brd_V3_OCP.brd")
		(comment 1 "Grand Teton / footprints 1299-1300 of 1440")
	)
	(layers
		(0 "F.Cu" signal "TOP")
		(4 "In1.Cu" signal "GND")
		(6 "In2.Cu" signal "IN1")
		(8 "In3.Cu" signal "GND1")
		(10 "In4.Cu" signal "IN2")
		(12 "In5.Cu" signal "VCC")
		(14 "In6.Cu" signal "VCC1")
		(16 "In7.Cu" signal "IN3")
		(18 "In8.Cu" signal "GND2")
		(20 "In9.Cu" signal "IN4")
		(22 "In10.Cu" signal "GND3")
		(2 "B.Cu" signal "BOTTOM")
		(9 "F.Adhes" user "F.Adhesive")
		(11 "B.Adhes" user "B.Adhesive")
		(13 "F.Paste" user "Package Geometry/Pastemask Top")
		(15 "B.Paste" user "Package Geometry/Pastemask Bottom")
		(5 "F.SilkS" user "Ref Des/Silkscreen Top")
		(7 "B.SilkS" user "Ref Des/Silkscreen Bottom")
		(1 "F.Mask" user "Board Geometry/Soldermask Top")
		(3 "B.Mask" user "Board Geometry/Soldermask Bottom")
		(17 "Dwgs.User" user "User.Drawings")
		(19 "Cmts.User" user "User.Comments")
		(21 "Eco1.User" user "User.Eco1")
		(23 "Eco2.User" user "User.Eco2")
		(25 "Edge.Cuts" user "Board Geometry/Outline")
		(27 "Margin" user)
		(31 "F.CrtYd" user "Package Geometry/Place Bound Top")
		(29 "B.CrtYd" user "Package Geometry/Place Bound Bottom")
		(35 "F.Fab" user "Ref Des/Assembly Top")
		(33 "B.Fab" user "Ref Des/Assembly Bottom")
	)
	(footprint ""
		(layer "B.Cu")
		(at 61.57722 -61.985906 -90)
		(property "Reference" "C25"
			(at 0 0 90)
			(layer "B.SilkS")
			(hide yes)
			(effects
				(font
					(size 1.27 1.27)
				)
				(justify mirror)
			)
		)
		(property "Value" ""
			(at 0 0 90)
			(layer "B.Fab")
			(effects
				(font
					(size 1.27 1.27)
				)
				(justify mirror)
			)
		)
		(duplicate_pad_numbers_are_jumpers no)
		(fp_line
			(start -0.7874 0.4064)
			(end 0.7874 0.4064)
			(stroke
				(width 0.1524)
				(type default)
			)
			(layer "B.SilkS")
		)
		(fp_line
			(start 0.7874 0.4064)
			(end 0.7874 -0.10414)
			(stroke
				(width 0.1524)
				(type default)
			)
			(layer "B.SilkS")
		)
		(fp_line
			(start -0.7874 -0.15494)
			(end -0.7874 0.4064)
			(stroke
				(width 0.1524)
				(type default)
			)
			(layer "B.SilkS")
		)
		(fp_line
			(start 0.489966 -0.4064)
			(end -0.480314 -0.4064)
			(stroke
				(width 0.1524)
				(type default)
			)
			(layer "B.SilkS")
		)
		(fp_line
			(start -0.67945 0.3048)
			(end -0.120396 0.3048)
			(stroke
				(width 0.1)
				(type default)
			)
			(layer "B.Fab")
		)
		(fp_line
			(start -0.120396 0.3048)
			(end -0.120396 0.2794)
			(stroke
				(width 0.1)
				(type default)
			)
			(layer "B.Fab")
		)
		(fp_line
			(start 0.12065 0.3048)
			(end 0.67945 0.3048)
			(stroke
				(width 0.1)
				(type default)
			)
			(layer "B.Fab")
		)
		(fp_line
			(start 0.67945 0.3048)
			(end 0.67945 -0.305054)
			(stroke
				(width 0.1)
				(type default)
			)
			(layer "B.Fab")
		)
		(fp_line
			(start -0.120396 0.2794)
			(end 0.12065 0.2794)
			(stroke
				(width 0.1)
				(type default)
			)
			(layer "B.Fab")
		)
		(fp_line
			(start 0.12065 0.2794)
			(end 0.12065 0.3048)
			(stroke
				(width 0.1)
				(type default)
			)
			(layer "B.Fab")
		)
		(fp_line
			(start -0.12065 -0.2794)
			(end -0.12065 -0.3048)
			(stroke
				(width 0.1)
				(type default)
			)
			(layer "B.Fab")
		)
		(fp_line
			(start 0.12065 -0.2794)
			(end -0.12065 -0.2794)
			(stroke
				(width 0.1)
				(type default)
			)
			(layer "B.Fab")
		)
		(fp_line
			(start -0.67945 -0.3048)
			(end -0.67945 0.3048)
			(stroke
				(width 0.1)
				(type default)
			)
			(layer "B.Fab")
		)
		(fp_line
			(start -0.12065 -0.3048)
			(end -0.67945 -0.3048)
			(stroke
				(width 0.1)
				(type default)
			)
			(layer "B.Fab")
		)
		(fp_line
			(start 0.12065 -0.305054)
			(end 0.12065 -0.2794)
			(stroke
				(width 0.1)
				(type default)
			)
			(layer "B.Fab")
		)
		(fp_line
			(start 0.67945 -0.305054)
			(end 0.12065 -0.305054)
			(stroke
				(width 0.1)
				(type default)
			)
			(layer "B.Fab")
		)
		(pad "1" smd circle
			(at 0.40005 0 90)
			(size 0 0)
			(layers "B.Cu" "B.Mask" "B.Paste")
			(net "P2E_PCH_TX_DN")
		)
		(pad "2" smd circle
			(at -0.40005 0 90)
			(size 0 0)
			(layers "B.Cu" "B.Mask" "B.Paste")
			(net "P2E_PCH_TX_C_DN")
		)
	)
	(footprint ""
		(layer "B.Cu")
		(at 30.988 -67.437 -90)
		(property "Reference" "U7"
			(at 1.0922 1.77927 270)
			(unlocked yes)
			(layer "B.SilkS")
			(effects
				(font
					(size 0.7874 0.5842)
					(thickness 0.1524)
				)
				(justify mirror)
			)
		)
		(property "Value" ""
			(at 0 0 90)
			(layer "B.Fab")
			(effects
				(font
					(size 1.27 1.27)
				)
				(justify mirror)
			)
		)
		(duplicate_pad_numbers_are_jumpers no)
		(fp_line
			(start -1.7272 1.1176)
			(end 1.7272 1.1176)
			(stroke
				(width 0.1524)
				(type default)
			)
			(layer "B.SilkS")
		)
		(fp_line
			(start 1.7272 1.1176)
			(end 1.7272 -1.1176)
			(stroke
				(width 0.1524)
				(type default)
			)
			(layer "B.SilkS")
		)
		(fp_line
			(start 0 -0.7366)
			(end 0.254 -1.1176)
			(stroke
				(width 0.1524)
				(type default)
			)
			(layer "B.SilkS")
		)
		(fp_line
			(start -1.7272 -1.1176)
			(end -1.7272 1.1176)
			(stroke
				(width 0.1524)
				(type default)
			)
			(layer "B.SilkS")
		)
		(fp_line
			(start -1.7272 -1.1176)
			(end -0.254 -1.1176)
			(stroke
				(width 0.1524)
				(type default)
			)
			(layer "B.SilkS")
		)
		(fp_line
			(start -0.254 -1.1176)
			(end 0 -0.7366)
			(stroke
				(width 0.1524)
				(type default)
			)
			(layer "B.SilkS")
		)
		(fp_line
			(start 0.254 -1.1176)
			(end 1.7272 -1.1176)
			(stroke
				(width 0.1524)
				(type default)
			)
			(layer "B.SilkS")
		)
		(fp_poly
			(pts
				(xy 2.9718 -0.395986) (xy 3.7338 -0.014986) (xy 3.7338 -0.776986)
			)
			(stroke
				(width 0)
				(type default)
			)
			(fill yes)
			(layer "B.SilkS")
		)
		(fp_line
			(start -1.5748 1.1176)
			(end -1.5748 -1.1176)
			(stroke
				(width 0.1)
				(type default)
			)
			(layer "B.Fab")
		)
		(fp_line
			(start 1.5748 1.1176)
			(end -1.5748 1.1176)
			(stroke
				(width 0.1)
				(type default)
			)
			(layer "B.Fab")
		)
		(fp_line
			(start -1.5748 -1.1176)
			(end 1.5748 -1.1176)
			(stroke
				(width 0.1)
				(type default)
			)
			(layer "B.Fab")
		)
		(fp_line
			(start 1.5748 -1.1176)
			(end 1.5748 1.1176)
			(stroke
				(width 0.1)
				(type default)
			)
			(layer "B.Fab")
		)
		(fp_poly
			(pts
				(xy 1.9558 -0.649986) (xy 2.7178 -0.268986) (xy 2.7178 -1.030986)
			)
			(stroke
				(width 0)
				(type default)
			)
			(fill yes)
			(layer "B.Fab")
		)
		(pad "1" smd rect
			(at 0.999998 -0.649986 180)
			(size 0.3556 1.1176)
			(layers "B.Cu" "B.Mask" "B.Paste")
			(net "SPA_SOUT_SW_DBG_R")
		)
		(pad "2" smd rect
			(at 0.999998 0 180)
			(size 0.3556 1.1176)
			(layers "B.Cu" "B.Mask" "B.Paste")
			(net "GND")
		)
		(pad "3" smd rect
			(at 0.999998 0.649986 180)
			(size 0.3556 1.1176)
			(layers "B.Cu" "B.Mask" "B.Paste")
			(net "UART_SYS_DBG_TX_R")
		)
		(pad "4" smd rect
			(at -0.999998 0.649986 180)
			(size 0.3556 1.1176)
			(layers "B.Cu" "B.Mask" "B.Paste")
			(net "SPA_SOUT_SW_BUF_R")
		)
		(pad "5" smd rect
			(at -0.999998 0 180)
			(size 0.3556 1.1176)
			(layers "B.Cu" "B.Mask" "B.Paste")
			(net "P3V3_AUX")
		)
		(pad "6" smd rect
			(at -0.999998 -0.649986 180)
			(size 0.3556 1.1176)
			(layers "B.Cu" "B.Mask" "B.Paste")
			(net "FM_DBG_SW_N")
		)
	)
)
